(kicad_pcb
	(version 20260206)
	(generator "pcbnew")
	(generator_version "10.0")
	(general
		(thickness 1.6)
		(legacy_teardrops no)
	)
	(paper "A4")
	(title_block
		(title "03242023_DA0F0TMBIJ0_F0T_Motherboard_J_brd_V01_OCP.brd")
		(comment 1 "Grand Teton / footprints 5387-5394 of 6105")
	)
	(layers
		(0 "F.Cu" signal "TOP")
		(4 "In1.Cu" signal "GND")
		(6 "In2.Cu" signal "IN1")
		(8 "In3.Cu" signal "GND1")
		(10 "In4.Cu" signal "IN2")
		(12 "In5.Cu" signal "GND2")
		(14 "In6.Cu" signal "IN3")
		(16 "In7.Cu" signal "GND3")
		(18 "In8.Cu" signal "VCC")
		(20 "In9.Cu" signal "VCC1")
		(22 "In10.Cu" signal "GND4")
		(24 "In11.Cu" signal "IN4")
		(26 "In12.Cu" signal "GND5")
		(28 "In13.Cu" signal "IN5")
		(30 "In14.Cu" signal "GND6")
		(32 "In15.Cu" signal "IN6")
		(34 "In16.Cu" signal "GND7")
		(2 "B.Cu" signal "BOTTOM")
		(9 "F.Adhes" user "F.Adhesive")
		(11 "B.Adhes" user "B.Adhesive")
		(13 "F.Paste" user "Package Geometry/Pastemask Top")
		(15 "B.Paste" user "Package Geometry/Pastemask Bottom")
		(5 "F.SilkS" user "Ref Des/Silkscreen Top")
		(7 "B.SilkS" user "Ref Des/Silkscreen Bottom")
		(1 "F.Mask" user "Board Geometry/Soldermask Top")
		(3 "B.Mask" user "Board Geometry/Soldermask Bottom")
		(17 "Dwgs.User" user "User.Drawings")
		(19 "Cmts.User" user "User.Comments")
		(21 "Eco1.User" user "User.Eco1")
		(23 "Eco2.User" user "User.Eco2")
		(25 "Edge.Cuts" user "Board Geometry/Outline")
		(27 "Margin" user)
		(31 "F.CrtYd" user "Package Geometry/Place Bound Top")
		(29 "B.CrtYd" user "Package Geometry/Place Bound Bottom")
		(35 "F.Fab" user "Ref Des/Assembly Top")
		(33 "B.Fab" user "Ref Des/Assembly Bottom")
	)
	(footprint ""
		(layer "B.Cu")
		(at 246.01932 -52.907946 -90)
		(property "Reference" "PC2280"
			(at 0 0 90)
			(layer "B.SilkS")
			(hide yes)
			(effects
				(font
					(size 1.27 1.27)
				)
				(justify mirror)
			)
		)
		(property "Value" ""
			(at 0 0 90)
			(layer "B.Fab")
			(effects
				(font
					(size 1.27 1.27)
				)
				(justify mirror)
			)
		)
		(duplicate_pad_numbers_are_jumpers no)
		(fp_line
			(start -1.524 0.762)
			(end 1.524 0.762)
			(stroke
				(width 0.1524)
				(type default)
			)
			(layer "B.SilkS")
		)
		(fp_line
			(start 1.524 0.762)
			(end 1.524 -0.762)
			(stroke
				(width 0.1524)
				(type default)
			)
			(layer "B.SilkS")
		)
		(fp_line
			(start -1.524 -0.762)
			(end -1.524 0.762)
			(stroke
				(width 0.1524)
				(type default)
			)
			(layer "B.SilkS")
		)
		(fp_line
			(start 1.524 -0.762)
			(end -1.524 -0.762)
			(stroke
				(width 0.1524)
				(type default)
			)
			(layer "B.SilkS")
		)
		(fp_line
			(start -1.1049 0.724916)
			(end -1.1049 -0.724916)
			(stroke
				(width 0.1)
				(type default)
			)
			(layer "B.Fab")
		)
		(fp_line
			(start 1.1049 0.724916)
			(end -1.1049 0.724916)
			(stroke
				(width 0.1)
				(type default)
			)
			(layer "B.Fab")
		)
		(fp_line
			(start -1.1049 -0.724916)
			(end 1.1049 -0.724916)
			(stroke
				(width 0.1)
				(type default)
			)
			(layer "B.Fab")
		)
		(fp_line
			(start 1.1049 -0.724916)
			(end 1.1049 0.724916)
			(stroke
				(width 0.1)
				(type default)
			)
			(layer "B.Fab")
		)
		(pad "1" smd rect
			(at 0.889 0 270)
			(size 1.016 1.27)
			(layers "B.Cu" "B.Mask" "B.Paste")
			(net "P12V_E1S_0")
		)
		(pad "2" smd rect
			(at -0.889 0 270)
			(size 1.016 1.27)
			(layers "B.Cu" "B.Mask" "B.Paste")
			(net "GND")
		)
	)
	(footprint ""
		(layer "B.Cu")
		(at 116.40312 -237.718092 90)
		(property "Reference" "C326"
			(at 0 0 90)
			(layer "B.SilkS")
			(hide yes)
			(effects
				(font
					(size 1.27 1.27)
				)
				(justify mirror)
			)
		)
		(property "Value" ""
			(at 0 0 90)
			(layer "B.Fab")
			(effects
				(font
					(size 1.27 1.27)
				)
				(justify mirror)
			)
		)
		(duplicate_pad_numbers_are_jumpers no)
		(fp_line
			(start 1.524 -0.762)
			(end -1.524 -0.762)
			(stroke
				(width 0.1524)
				(type default)
			)
			(layer "B.SilkS")
		)
		(fp_line
			(start -1.524 -0.762)
			(end -1.524 0.762)
			(stroke
				(width 0.1524)
				(type default)
			)
			(layer "B.SilkS")
		)
		(fp_line
			(start 1.524 0.762)
			(end 1.524 -0.762)
			(stroke
				(width 0.1524)
				(type default)
			)
			(layer "B.SilkS")
		)
		(fp_line
			(start -1.524 0.762)
			(end 1.524 0.762)
			(stroke
				(width 0.1524)
				(type default)
			)
			(layer "B.SilkS")
		)
		(fp_line
			(start 1.1049 -0.724916)
			(end 1.1049 0.724916)
			(stroke
				(width 0.1)
				(type default)
			)
			(layer "B.Fab")
		)
		(fp_line
			(start -1.1049 -0.724916)
			(end 1.1049 -0.724916)
			(stroke
				(width 0.1)
				(type default)
			)
			(layer "B.Fab")
		)
		(fp_line
			(start 1.1049 0.724916)
			(end -1.1049 0.724916)
			(stroke
				(width 0.1)
				(type default)
			)
			(layer "B.Fab")
		)
		(fp_line
			(start -1.1049 0.724916)
			(end -1.1049 -0.724916)
			(stroke
				(width 0.1)
				(type default)
			)
			(layer "B.Fab")
		)
		(pad "1" smd rect
			(at 0.889 0 90)
			(size 1.016 1.27)
			(layers "B.Cu" "B.Mask" "B.Paste")
			(net "PVCCIN_CPU1")
		)
		(pad "2" smd rect
			(at -0.889 0 90)
			(size 1.016 1.27)
			(layers "B.Cu" "B.Mask" "B.Paste")
			(net "GND")
		)
	)
	(footprint ""
		(layer "B.Cu")
		(at 236.20095 -50.193448 180)
		(property "Reference" "R3771"
			(at 0 0 0)
			(layer "B.SilkS")
			(hide yes)
			(effects
				(font
					(size 1.27 1.27)
				)
				(justify mirror)
			)
		)
		(property "Value" ""
			(at 0 0 0)
			(layer "B.Fab")
			(effects
				(font
					(size 1.27 1.27)
				)
				(justify mirror)
			)
		)
		(duplicate_pad_numbers_are_jumpers no)
		(fp_line
			(start 0.7874 0.4064)
			(end 0.7874 -0.4064)
			(stroke
				(width 0.1524)
				(type default)
			)
			(layer "B.SilkS")
		)
		(fp_line
			(start 0.7874 -0.4064)
			(end -0.7874 -0.4064)
			(stroke
				(width 0.1524)
				(type default)
			)
			(layer "B.SilkS")
		)
		(fp_line
			(start -0.7874 0.4064)
			(end 0.7874 0.4064)
			(stroke
				(width 0.1524)
				(type default)
			)
			(layer "B.SilkS")
		)
		(fp_line
			(start -0.7874 -0.4064)
			(end -0.7874 0.4064)
			(stroke
				(width 0.1524)
				(type default)
			)
			(layer "B.SilkS")
		)
		(fp_line
			(start 0.67945 0.3048)
			(end 0.67945 -0.305054)
			(stroke
				(width 0.1)
				(type default)
			)
			(layer "B.Fab")
		)
		(fp_line
			(start 0.67945 -0.305054)
			(end 0.12065 -0.305054)
			(stroke
				(width 0.1)
				(type default)
			)
			(layer "B.Fab")
		)
		(fp_line
			(start 0.12065 0.3048)
			(end 0.67945 0.3048)
			(stroke
				(width 0.1)
				(type default)
			)
			(layer "B.Fab")
		)
		(fp_line
			(start 0.12065 0.2794)
			(end 0.12065 0.3048)
			(stroke
				(width 0.1)
				(type default)
			)
			(layer "B.Fab")
		)
		(fp_line
			(start 0.12065 -0.2794)
			(end -0.12065 -0.2794)
			(stroke
				(width 0.1)
				(type default)
			)
			(layer "B.Fab")
		)
		(fp_line
			(start 0.12065 -0.305054)
			(end 0.12065 -0.2794)
			(stroke
				(width 0.1)
				(type default)
			)
			(layer "B.Fab")
		)
		(fp_line
			(start -0.120396 0.3048)
			(end -0.120396 0.2794)
			(stroke
				(width 0.1)
				(type default)
			)
			(layer "B.Fab")
		)
		(fp_line
			(start -0.120396 0.2794)
			(end 0.12065 0.2794)
			(stroke
				(width 0.1)
				(type default)
			)
			(layer "B.Fab")
		)
		(fp_line
			(start -0.12065 -0.2794)
			(end -0.12065 -0.3048)
			(stroke
				(width 0.1)
				(type default)
			)
			(layer "B.Fab")
		)
		(fp_line
			(start -0.12065 -0.3048)
			(end -0.67945 -0.3048)
			(stroke
				(width 0.1)
				(type default)
			)
			(layer "B.Fab")
		)
		(fp_line
			(start -0.67945 0.3048)
			(end -0.120396 0.3048)
			(stroke
				(width 0.1)
				(type default)
			)
			(layer "B.Fab")
		)
		(fp_line
			(start -0.67945 -0.3048)
			(end -0.67945 0.3048)
			(stroke
				(width 0.1)
				(type default)
			)
			(layer "B.Fab")
		)
		(pad "1" smd circle
			(at 0.40005 0)
			(size 0 0)
			(layers "B.Cu" "B.Mask" "B.Paste")
			(net "P3V3_AUX")
		)
		(pad "2" smd circle
			(at -0.40005 0)
			(size 0 0)
			(layers "B.Cu" "B.Mask" "B.Paste")
			(net "E1S_0_PWRDIS")
		)
	)
	(footprint ""
		(layer "B.Cu")
		(at 196.906896 -193.267584)
		(property "Reference" "U23"
			(at 1.524 -1.87833 0)
			(unlocked yes)
			(layer "B.SilkS")
			(effects
				(font
					(size 0.7874 0.5842)
					(thickness 0.1524)
				)
				(justify left mirror)
			)
		)
		(property "Value" ""
			(at 0 0 0)
			(layer "B.Fab")
			(effects
				(font
					(size 1.27 1.27)
				)
				(justify mirror)
			)
		)
		(duplicate_pad_numbers_are_jumpers no)
		(fp_line
			(start -1.4986 -1.100074)
			(end -1.4986 1.100074)
			(stroke
				(width 0.1524)
				(type default)
			)
			(layer "B.SilkS")
		)
		(fp_line
			(start -1.4986 1.100074)
			(end 1.4986 1.100074)
			(stroke
				(width 0.1524)
				(type default)
			)
			(layer "B.SilkS")
		)
		(fp_line
			(start 1.4986 -1.100074)
			(end -1.4986 -1.100074)
			(stroke
				(width 0.1524)
				(type default)
			)
			(layer "B.SilkS")
		)
		(fp_line
			(start 1.4986 1.100074)
			(end 1.4986 -1.100074)
			(stroke
				(width 0.1524)
				(type default)
			)
			(layer "B.SilkS")
		)
		(fp_poly
			(pts
				(xy 2.15138 -0.417068) (xy 1.59766 -0.71374) (xy 2.15138 -1.041908)
			)
			(stroke
				(width 0)
				(type default)
			)
			(fill yes)
			(layer "B.SilkS")
		)
		(fp_line
			(start -0.67437 -1.100074)
			(end -0.67437 1.100074)
			(stroke
				(width 0.1)
				(type default)
			)
			(layer "B.Fab")
		)
		(fp_line
			(start -0.67437 1.100074)
			(end 0.67437 1.100074)
			(stroke
				(width 0.1)
				(type default)
			)
			(layer "B.Fab")
		)
		(fp_line
			(start 0.67437 -1.100074)
			(end -0.67437 -1.100074)
			(stroke
				(width 0.1)
				(type default)
			)
			(layer "B.Fab")
		)
		(fp_line
			(start 0.67437 1.100074)
			(end 0.67437 -1.100074)
			(stroke
				(width 0.1)
				(type default)
			)
			(layer "B.Fab")
		)
		(fp_poly
			(pts
				(xy 2.20472 -0.338328) (xy 2.20472 -0.963168) (xy 1.651 -0.635)
			)
			(stroke
				(width 0)
				(type default)
			)
			(fill yes)
			(layer "B.Fab")
		)
		(pad "1" smd rect
			(at 0.889 -0.649986 180)
			(size 1.016 0.381)
			(layers "B.Cu" "B.Mask" "B.Paste")
			(net "FM_CPU1_SKTOCC_N")
		)
		(pad "2" smd rect
			(at 0.889 0 180)
			(size 1.016 0.381)
			(layers "B.Cu" "B.Mask" "B.Paste")
			(net "FM_CPU0_SKTOCC_N")
		)
		(pad "3" smd rect
			(at 0.889 0.649986 180)
			(size 1.016 0.381)
			(layers "B.Cu" "B.Mask" "B.Paste")
			(net "GND")
		)
		(pad "4" smd rect
			(at -0.889 0.649986 180)
			(size 1.016 0.381)
			(layers "B.Cu" "B.Mask" "B.Paste")
			(net "FM_CPU_EN")
		)
		(pad "5" smd rect
			(at -0.889 -0.649986 180)
			(size 1.016 0.381)
			(layers "B.Cu" "B.Mask" "B.Paste")
			(net "P3V3_AUX")
		)
	)
	(footprint ""
		(layer "B.Cu")
		(at 353.619308 -259.531866 90)
		(property "Reference" "C501"
			(at 0 0 90)
			(layer "B.SilkS")
			(hide yes)
			(effects
				(font
					(size 1.27 1.27)
				)
				(justify mirror)
			)
		)
		(property "Value" ""
			(at 0 0 90)
			(layer "B.Fab")
			(effects
				(font
					(size 1.27 1.27)
				)
				(justify mirror)
			)
		)
		(duplicate_pad_numbers_are_jumpers no)
		(fp_line
			(start 1.524 -0.762)
			(end -1.524 -0.762)
			(stroke
				(width 0.1524)
				(type default)
			)
			(layer "B.SilkS")
		)
		(fp_line
			(start -1.524 -0.762)
			(end -1.524 0.762)
			(stroke
				(width 0.1524)
				(type default)
			)
			(layer "B.SilkS")
		)
		(fp_line
			(start 1.524 0.762)
			(end 1.524 -0.762)
			(stroke
				(width 0.1524)
				(type default)
			)
			(layer "B.SilkS")
		)
		(fp_line
			(start -1.524 0.762)
			(end 1.524 0.762)
			(stroke
				(width 0.1524)
				(type default)
			)
			(layer "B.SilkS")
		)
		(fp_line
			(start 1.1049 -0.724916)
			(end 1.1049 0.724916)
			(stroke
				(width 0.1)
				(type default)
			)
			(layer "B.Fab")
		)
		(fp_line
			(start -1.1049 -0.724916)
			(end 1.1049 -0.724916)
			(stroke
				(width 0.1)
				(type default)
			)
			(layer "B.Fab")
		)
		(fp_line
			(start 1.1049 0.724916)
			(end -1.1049 0.724916)
			(stroke
				(width 0.1)
				(type default)
			)
			(layer "B.Fab")
		)
		(fp_line
			(start -1.1049 0.724916)
			(end -1.1049 -0.724916)
			(stroke
				(width 0.1)
				(type default)
			)
			(layer "B.Fab")
		)
		(pad "1" smd rect
			(at 0.889 0 90)
			(size 1.016 1.27)
			(layers "B.Cu" "B.Mask" "B.Paste")
			(net "PVCCFA_EHV_FIVRA_CPU0")
		)
		(pad "2" smd rect
			(at -0.889 0 90)
			(size 1.016 1.27)
			(layers "B.Cu" "B.Mask" "B.Paste")
			(net "GND")
		)
	)
	(footprint ""
		(layer "B.Cu")
		(at 407.91257 -167.350948 180)
		(property "Reference" "PC204_P0_1"
			(at 0 0 0)
			(layer "B.SilkS")
			(hide yes)
			(effects
				(font
					(size 1.27 1.27)
				)
				(justify mirror)
			)
		)
		(property "Value" ""
			(at 0 0 0)
			(layer "B.Fab")
			(effects
				(font
					(size 1.27 1.27)
				)
				(justify mirror)
			)
		)
		(duplicate_pad_numbers_are_jumpers no)
		(fp_line
			(start 1.524 0.762)
			(end 1.524 -0.762)
			(stroke
				(width 0.1524)
				(type default)
			)
			(layer "B.SilkS")
		)
		(fp_line
			(start 1.524 -0.762)
			(end -1.524 -0.762)
			(stroke
				(width 0.1524)
				(type default)
			)
			(layer "B.SilkS")
		)
		(fp_line
			(start -1.524 0.762)
			(end 1.524 0.762)
			(stroke
				(width 0.1524)
				(type default)
			)
			(layer "B.SilkS")
		)
		(fp_line
			(start -1.524 -0.762)
			(end -1.524 0.762)
			(stroke
				(width 0.1524)
				(type default)
			)
			(layer "B.SilkS")
		)
		(fp_line
			(start 1.1049 0.724916)
			(end -1.1049 0.724916)
			(stroke
				(width 0.1)
				(type default)
			)
			(layer "B.Fab")
		)
		(fp_line
			(start 1.1049 -0.724916)
			(end 1.1049 0.724916)
			(stroke
				(width 0.1)
				(type default)
			)
			(layer "B.Fab")
		)
		(fp_line
			(start -1.1049 0.724916)
			(end -1.1049 -0.724916)
			(stroke
				(width 0.1)
				(type default)
			)
			(layer "B.Fab")
		)
		(fp_line
			(start -1.1049 -0.724916)
			(end 1.1049 -0.724916)
			(stroke
				(width 0.1)
				(type default)
			)
			(layer "B.Fab")
		)
		(pad "1" smd rect
			(at 0.889 0 180)
			(size 1.016 1.27)
			(layers "B.Cu" "B.Mask" "B.Paste")
			(net "PVCCINFAON_CPU0")
		)
		(pad "2" smd rect
			(at -0.889 0 180)
			(size 1.016 1.27)
			(layers "B.Cu" "B.Mask" "B.Paste")
			(net "GND")
		)
	)
	(footprint ""
		(layer "B.Cu")
		(at 448.22872 -78.115668 90)
		(property "Reference" "R3117"
			(at 0 0 90)
			(layer "B.SilkS")
			(hide yes)
			(effects
				(font
					(size 1.27 1.27)
				)
				(justify mirror)
			)
		)
		(property "Value" ""
			(at 0 0 90)
			(layer "B.Fab")
			(effects
				(font
					(size 1.27 1.27)
				)
				(justify mirror)
			)
		)
		(duplicate_pad_numbers_are_jumpers no)
		(fp_line
			(start 0.7874 -0.4064)
			(end -0.7874 -0.4064)
			(stroke
				(width 0.1524)
				(type default)
			)
			(layer "B.SilkS")
		)
		(fp_line
			(start -0.7874 -0.4064)
			(end -0.7874 0.4064)
			(stroke
				(width 0.1524)
				(type default)
			)
			(layer "B.SilkS")
		)
		(fp_line
			(start 0.7874 0.4064)
			(end 0.7874 -0.4064)
			(stroke
				(width 0.1524)
				(type default)
			)
			(layer "B.SilkS")
		)
		(fp_line
			(start -0.7874 0.4064)
			(end 0.7874 0.4064)
			(stroke
				(width 0.1524)
				(type default)
			)
			(layer "B.SilkS")
		)
		(fp_line
			(start 0.67945 -0.305054)
			(end 0.12065 -0.305054)
			(stroke
				(width 0.1)
				(type default)
			)
			(layer "B.Fab")
		)
		(fp_line
			(start 0.12065 -0.305054)
			(end 0.12065 -0.2794)
			(stroke
				(width 0.1)
				(type default)
			)
			(layer "B.Fab")
		)
		(fp_line
			(start -0.12065 -0.3048)
			(end -0.67945 -0.3048)
			(stroke
				(width 0.1)
				(type default)
			)
			(layer "B.Fab")
		)
		(fp_line
			(start -0.67945 -0.3048)
			(end -0.67945 0.3048)
			(stroke
				(width 0.1)
				(type default)
			)
			(layer "B.Fab")
		)
		(fp_line
			(start 0.12065 -0.2794)
			(end -0.12065 -0.2794)
			(stroke
				(width 0.1)
				(type default)
			)
			(layer "B.Fab")
		)
		(fp_line
			(start -0.12065 -0.2794)
			(end -0.12065 -0.3048)
			(stroke
				(width 0.1)
				(type default)
			)
			(layer "B.Fab")
		)
		(fp_line
			(start 0.12065 0.2794)
			(end 0.12065 0.3048)
			(stroke
				(width 0.1)
				(type default)
			)
			(layer "B.Fab")
		)
		(fp_line
			(start -0.120396 0.2794)
			(end 0.12065 0.2794)
			(stroke
				(width 0.1)
				(type default)
			)
			(layer "B.Fab")
		)
		(fp_line
			(start 0.67945 0.3048)
			(end 0.67945 -0.305054)
			(stroke
				(width 0.1)
				(type default)
			)
			(layer "B.Fab")
		)
		(fp_line
			(start 0.12065 0.3048)
			(end 0.67945 0.3048)
			(stroke
				(width 0.1)
				(type default)
			)
			(layer "B.Fab")
		)
		(fp_line
			(start -0.120396 0.3048)
			(end -0.120396 0.2794)
			(stroke
				(width 0.1)
				(type default)
			)
			(layer "B.Fab")
		)
		(fp_line
			(start -0.67945 0.3048)
			(end -0.120396 0.3048)
			(stroke
				(width 0.1)
				(type default)
			)
			(layer "B.Fab")
		)
		(pad "1" smd circle
			(at 0.40005 0 270)
			(size 0 0)
			(layers "B.Cu" "B.Mask" "B.Paste")
			(net "P12V_AUX")
		)
		(pad "2" smd circle
			(at -0.40005 0 270)
			(size 0 0)
			(layers "B.Cu" "B.Mask" "B.Paste")
			(net "P3V3_AUX_EN")
		)
	)
	(footprint ""
		(layer "B.Cu")
		(at 76.413106 -334.566514 -90)
		(property "Reference" "PR574"
			(at 0 0 90)
			(layer "B.SilkS")
			(hide yes)
			(effects
				(font
					(size 1.27 1.27)
				)
				(justify mirror)
			)
		)
		(property "Value" ""
			(at 0 0 90)
			(layer "B.Fab")
			(effects
				(font
					(size 1.27 1.27)
				)
				(justify mirror)
			)
		)
		(duplicate_pad_numbers_are_jumpers no)
		(fp_line
			(start -0.7874 0.4064)
			(end 0.7874 0.4064)
			(stroke
				(width 0.1524)
				(type default)
			)
			(layer "B.SilkS")
		)
		(fp_line
			(start 0.7874 0.4064)
			(end 0.7874 -0.4064)
			(stroke
				(width 0.1524)
				(type default)
			)
			(layer "B.SilkS")
		)
		(fp_line
			(start -0.7874 -0.4064)
			(end -0.7874 0.4064)
			(stroke
				(width 0.1524)
				(type default)
			)
			(layer "B.SilkS")
		)
		(fp_line
			(start 0.7874 -0.4064)
			(end -0.7874 -0.4064)
			(stroke
				(width 0.1524)
				(type default)
			)
			(layer "B.SilkS")
		)
		(fp_line
			(start -0.67945 0.3048)
			(end -0.120396 0.3048)
			(stroke
				(width 0.1)
				(type default)
			)
			(layer "B.Fab")
		)
		(fp_line
			(start -0.120396 0.3048)
			(end -0.120396 0.2794)
			(stroke
				(width 0.1)
				(type default)
			)
			(layer "B.Fab")
		)
		(fp_line
			(start 0.12065 0.3048)
			(end 0.67945 0.3048)
			(stroke
				(width 0.1)
				(type default)
			)
			(layer "B.Fab")
		)
		(fp_line
			(start 0.67945 0.3048)
			(end 0.67945 -0.305054)
			(stroke
				(width 0.1)
				(type default)
			)
			(layer "B.Fab")
		)
		(fp_line
			(start -0.120396 0.2794)
			(end 0.12065 0.2794)
			(stroke
				(width 0.1)
				(type default)
			)
			(layer "B.Fab")
		)
		(fp_line
			(start 0.12065 0.2794)
			(end 0.12065 0.3048)
			(stroke
				(width 0.1)
				(type default)
			)
			(layer "B.Fab")
		)
		(fp_line
			(start -0.12065 -0.2794)
			(end -0.12065 -0.3048)
			(stroke
				(width 0.1)
				(type default)
			)
			(layer "B.Fab")
		)
		(fp_line
			(start 0.12065 -0.2794)
			(end -0.12065 -0.2794)
			(stroke
				(width 0.1)
				(type default)
			)
			(layer "B.Fab")
		)
		(fp_line
			(start -0.67945 -0.3048)
			(end -0.67945 0.3048)
			(stroke
				(width 0.1)
				(type default)
			)
			(layer "B.Fab")
		)
		(fp_line
			(start -0.12065 -0.3048)
			(end -0.67945 -0.3048)
			(stroke
				(width 0.1)
				(type default)
			)
			(layer "B.Fab")
		)
		(fp_line
			(start 0.12065 -0.305054)
			(end 0.12065 -0.2794)
			(stroke
				(width 0.1)
				(type default)
			)
			(layer "B.Fab")
		)
		(fp_line
			(start 0.67945 -0.305054)
			(end 0.12065 -0.305054)
			(stroke
				(width 0.1)
				(type default)
			)
			(layer "B.Fab")
		)
		(pad "1" smd circle
			(at 0.40005 0 90)
			(size 0 0)
			(layers "B.Cu" "B.Mask" "B.Paste")
			(net "VSENSE_PVCCIN_CPU1_DN")
		)
		(pad "2" smd circle
			(at -0.40005 0 90)
			(size 0 0)
			(layers "B.Cu" "B.Mask" "B.Paste")
			(net "GND")
		)
	)
)
